(kicad_pcb
	(version 20260206)
	(generator "pcbnew")
	(generator_version "10.0")
	(general
		(thickness 1.6)
		(legacy_teardrops no)
	)
	(paper "A4")
	(title_block
		(title "fcb — 12433-1M.1206WZS1330.brd")
		(comment 1 "Open Vault / Knox (Wiwynn) / footprints 151-156 of 495")
	)
	(layers
		(0 "F.Cu" signal "TOP")
		(4 "In1.Cu" signal "L2GND")
		(6 "In2.Cu" signal "L3VCC")
		(2 "B.Cu" signal "BOTTOM")
		(9 "F.Adhes" user "F.Adhesive")
		(11 "B.Adhes" user "B.Adhesive")
		(13 "F.Paste" user "Package Geometry/Pastemask Top")
		(15 "B.Paste" user "Package Geometry/Pastemask Bottom")
		(5 "F.SilkS" user "Ref Des/Silkscreen Top")
		(7 "B.SilkS" user "Ref Des/Silkscreen Bottom")
		(1 "F.Mask" user "Board Geometry/Soldermask Top")
		(3 "B.Mask" user "Board Geometry/Soldermask Bottom")
		(17 "Dwgs.User" user "User.Drawings")
		(19 "Cmts.User" user "User.Comments")
		(21 "Eco1.User" user "User.Eco1")
		(23 "Eco2.User" user "User.Eco2")
		(25 "Edge.Cuts" user "Board Geometry/Outline")
		(27 "Margin" user)
		(31 "F.CrtYd" user "Package Geometry/Place Bound Top")
		(29 "B.CrtYd" user "Package Geometry/Place Bound Bottom")
		(35 "F.Fab" user "Ref Des/Assembly Top")
		(33 "B.Fab" user "Ref Des/Assembly Bottom")
	)
	(footprint ""
		(layer "F.Cu")
		(at 6.999986 -39.99992)
		(property "Reference" "H2"
			(at 0 0 0)
			(layer "F.SilkS")
			(hide yes)
			(effects
				(font
					(size 1.27 1.27)
				)
			)
		)
		(property "Value" "HOLE315R158"
			(at -5.08 -0.4572 0)
			(unlocked yes)
			(layer "F.Fab")
			(hide yes)
			(effects
				(font
					(size 1.016 1.016)
					(thickness 0.1524)
				)
			)
		)
		(property "Device Type" "HOLE315R158"
			(at -5.08 -1.9812 0)
			(unlocked yes)
			(layer "F.Fab")
			(hide yes)
			(effects
				(font
					(size 1.016 1.016)
					(thickness 0.1524)
				)
			)
		)
		(duplicate_pad_numbers_are_jumpers no)
		(fp_poly
			(pts
				(arc
					(start -4.3053 0)
					(mid 4.3053 0)
					(end -4.3053 0)
				)
			)
			(stroke
				(width 0)
				(type default)
			)
			(fill no)
			(layer "B.CrtYd")
		)
		(fp_poly
			(pts
				(arc
					(start -4.3053 0)
					(mid 4.3053 0)
					(end -4.3053 0)
				)
			)
			(stroke
				(width 0)
				(type default)
			)
			(fill no)
			(layer "F.CrtYd")
		)
		(fp_poly
			(pts
				(arc
					(start -4.3053 0)
					(mid 4.3053 0)
					(end -4.3053 0)
				)
			)
			(stroke
				(width 0)
				(type default)
			)
			(fill no)
			(layer "B.Fab")
		)
		(fp_poly
			(pts
				(arc
					(start -4.3053 0)
					(mid 4.3053 0)
					(end -4.3053 0)
				)
			)
			(stroke
				(width 0)
				(type default)
			)
			(fill no)
			(layer "F.Fab")
		)
		(pad "1" thru_hole circle
			(at 0 0)
			(size 8.001 8.001)
			(drill 4.0132)
			(layers "*.Cu" "*.Mask")
			(remove_unused_layers no)
			(net "GND")
			(clearance -1.4859)
			(thermal_gap 0.3048)
			(padstack
				(mode front_inner_back)
				(layer "Inner"
					(shape circle)
					(size 4.4196 4.4196)
					(clearance 0.3048)
				)
				(layer "B.Cu"
					(shape circle)
					(size 8.001 8.001)
					(clearance -1.4859)
				)
			)
		)
	)
	(footprint ""
		(layer "F.Cu")
		(at 4.040124 -17.29994 -90)
		(property "Reference" "CN6"
			(at 0 0 270)
			(layer "F.SilkS")
			(hide yes)
			(effects
				(font
					(size 1.27 1.27)
				)
			)
		)
		(property "Value" "JWT-CON5-42-GP"
			(at -7.8105 2.9591 270)
			(unlocked yes)
			(layer "F.Fab")
			(hide yes)
			(effects
				(font
					(size 1.016 1.016)
					(thickness 0.1524)
				)
			)
		)
		(property "Device Type" "A2541WR0-1TX5PA-6T-0E"
			(at -7.8105 1.4351 270)
			(unlocked yes)
			(layer "F.Fab")
			(hide yes)
			(effects
				(font
					(size 1.016 1.016)
					(thickness 0.1524)
				)
			)
		)
		(duplicate_pad_numbers_are_jumpers no)
		(fp_line
			(start -6.604 10.287)
			(end 6.604 10.287)
			(stroke
				(width 0.1524)
				(type default)
			)
			(layer "F.SilkS")
		)
		(fp_line
			(start 6.604 10.287)
			(end 6.604 -0.9652)
			(stroke
				(width 0.1524)
				(type default)
			)
			(layer "F.SilkS")
		)
		(fp_line
			(start -6.604 -0.9652)
			(end -6.604 10.287)
			(stroke
				(width 0.1524)
				(type default)
			)
			(layer "F.SilkS")
		)
		(fp_line
			(start 6.604 -0.9652)
			(end -6.604 -0.9652)
			(stroke
				(width 0.1524)
				(type default)
			)
			(layer "F.SilkS")
		)
		(fp_line
			(start -6.731 -1.0922)
			(end -6.731 0.1778)
			(stroke
				(width 0.4064)
				(type default)
			)
			(layer "F.SilkS")
		)
		(fp_line
			(start -5.461 -1.0922)
			(end -6.731 -1.0922)
			(stroke
				(width 0.4064)
				(type default)
			)
			(layer "F.SilkS")
		)
		(fp_circle
			(center -5.08 0)
			(end -5.08 -1.0668)
			(stroke
				(width 0.3048)
				(type default)
			)
			(fill no)
			(layer "F.SilkS")
		)
		(fp_circle
			(center -2.54 0)
			(end -2.54 -1.0668)
			(stroke
				(width 0.3048)
				(type default)
			)
			(fill no)
			(layer "F.SilkS")
		)
		(fp_circle
			(center 0 0)
			(end 0 -1.0668)
			(stroke
				(width 0.3048)
				(type default)
			)
			(fill no)
			(layer "F.SilkS")
		)
		(fp_circle
			(center 2.54 0)
			(end 2.54 -1.0668)
			(stroke
				(width 0.3048)
				(type default)
			)
			(fill no)
			(layer "F.SilkS")
		)
		(fp_circle
			(center 5.08 0)
			(end 5.08 -1.0668)
			(stroke
				(width 0.3048)
				(type default)
			)
			(fill no)
			(layer "F.SilkS")
		)
		(fp_rect
			(start -6.35 10.033)
			(end 6.35 -0.3302)
			(stroke
				(width 0)
				(type default)
			)
			(fill no)
			(layer "F.CrtYd")
		)
		(fp_poly
			(pts
				(xy -6.35 -0.3302) (xy 6.858 -0.3302) (xy 6.858 -1.2192) (xy -6.858 -1.2192) (xy -6.858 10.541)
				(xy 6.858 10.541) (xy 6.858 -0.3175) (xy 6.35 -0.3175) (xy 6.35 10.033) (xy -6.35 10.033)
			)
			(stroke
				(width 0)
				(type default)
			)
			(fill no)
			(layer "F.CrtYd")
		)
		(fp_rect
			(start -6.858 10.541)
			(end 6.858 -1.2192)
			(stroke
				(width 0)
				(type default)
			)
			(fill no)
			(layer "F.Fab")
		)
		(pad "1" thru_hole circle
			(at -5.08 0 270)
			(size 1.4224 1.4224)
			(drill 1.016)
			(layers "*.Cu" "*.Mask")
			(remove_unused_layers no)
			(net "GND")
			(clearance 0.1524)
			(thermal_gap 0.1524)
		)
		(pad "2" thru_hole circle
			(at -2.54 0 270)
			(size 1.4224 1.4224)
			(drill 1.016)
			(layers "*.Cu" "*.Mask")
			(remove_unused_layers no)
			(net "P12V_FAN6")
			(clearance 0.1524)
			(thermal_gap 0.1524)
		)
		(pad "3" thru_hole circle
			(at 0 0 270)
			(size 1.4224 1.4224)
			(drill 1.016)
			(layers "*.Cu" "*.Mask")
			(remove_unused_layers no)
			(net "FAN_TACH12")
			(clearance 0.1524)
			(thermal_gap 0.1524)
		)
		(pad "4" thru_hole circle
			(at 2.54 0 270)
			(size 1.4224 1.4224)
			(drill 1.016)
			(layers "*.Cu" "*.Mask")
			(remove_unused_layers no)
			(net "PWM_OUT_FAN6_NET")
			(clearance 0.1524)
			(thermal_gap 0.1524)
		)
		(pad "5" thru_hole circle
			(at 5.08 0 270)
			(size 1.4224 1.4224)
			(drill 1.016)
			(layers "*.Cu" "*.Mask")
			(remove_unused_layers no)
			(net "FAN_TACH11")
			(clearance 0.1524)
			(thermal_gap 0.1524)
		)
	)
	(footprint ""
		(layer "F.Cu")
		(at 47.0154 -419.7858 90)
		(property "Reference" "C26"
			(at 0 0 90)
			(layer "F.SilkS")
			(hide yes)
			(effects
				(font
					(size 1.27 1.27)
				)
			)
		)
		(property "Value" "SC1U25V3KX-1-GP"
			(at 0 -2.8194 90)
			(unlocked yes)
			(layer "F.Fab")
			(hide yes)
			(effects
				(font
					(size 1.016 1.016)
					(thickness 0.1524)
				)
			)
		)
		(property "Device Type" "C603H36"
			(at 0 -4.3434 90)
			(unlocked yes)
			(layer "F.Fab")
			(hide yes)
			(effects
				(font
					(size 1.016 1.016)
					(thickness 0.1524)
				)
			)
		)
		(duplicate_pad_numbers_are_jumpers no)
		(fp_line
			(start 0.508 0)
			(end -0.508 0)
			(stroke
				(width 0.2032)
				(type default)
			)
			(layer "F.SilkS")
		)
		(fp_rect
			(start -0.5842 1.3335)
			(end 0.5842 -1.3335)
			(stroke
				(width 0)
				(type default)
			)
			(fill no)
			(layer "F.CrtYd")
		)
		(fp_rect
			(start -0.5842 1.3335)
			(end 0.5842 -1.3335)
			(stroke
				(width 0)
				(type default)
			)
			(fill no)
			(layer "F.Fab")
		)
		(pad "1" smd custom
			(at 0 -0.762 90)
			(size 0.2159 0.2159)
			(layers "F.Cu" "F.Mask" "F.Paste")
			(net "P12V_AUX")
			(options
				(clearance outline)
				(anchor circle)
			)
			(primitives
				(gr_poly
					(pts
						(arc
							(start -0.3302 -0.4318)
							(mid -0.402042 -0.402042)
							(end -0.4318 -0.3302)
						)
						(arc
							(start -0.4318 0.3302)
							(mid -0.402042 0.402042)
							(end -0.3302 0.4318)
						)
						(arc
							(start 0.3302 0.4318)
							(mid 0.402042 0.402042)
							(end 0.4318 0.3302)
						)
						(arc
							(start 0.4318 -0.3302)
							(mid 0.402042 -0.402042)
							(end 0.3302 -0.4318)
						)
					)
					(width 0)
					(fill yes)
				)
			)
		)
		(pad "2" smd custom
			(at 0 0.762 90)
			(size 0.2159 0.2159)
			(layers "F.Cu" "F.Mask" "F.Paste")
			(net "GND")
			(options
				(clearance outline)
				(anchor circle)
			)
			(primitives
				(gr_poly
					(pts
						(arc
							(start -0.3302 -0.4318)
							(mid -0.402042 -0.402042)
							(end -0.4318 -0.3302)
						)
						(arc
							(start -0.4318 0.3302)
							(mid -0.402042 0.402042)
							(end -0.3302 0.4318)
						)
						(arc
							(start 0.3302 0.4318)
							(mid 0.402042 0.402042)
							(end 0.4318 0.3302)
						)
						(arc
							(start 0.4318 -0.3302)
							(mid 0.402042 -0.402042)
							(end 0.3302 -0.4318)
						)
					)
					(width 0)
					(fill yes)
				)
			)
		)
	)
	(footprint ""
		(layer "F.Cu")
		(at 39.784274 -363.062774 180)
		(property "Reference" "PR42"
			(at 0 0 180)
			(layer "F.SilkS")
			(hide yes)
			(effects
				(font
					(size 1.27 1.27)
				)
			)
		)
		(property "Value" "10KR2F-2-GP"
			(at 0.064008 -3.993896 180)
			(unlocked yes)
			(layer "F.Fab")
			(hide yes)
			(effects
				(font
					(size 1.016 1.016)
					(thickness 0.1524)
				)
			)
		)
		(property "Device Type" "R402H16"
			(at 0.064008 -5.517896 180)
			(unlocked yes)
			(layer "F.Fab")
			(hide yes)
			(effects
				(font
					(size 1.016 1.016)
					(thickness 0.1524)
				)
			)
		)
		(duplicate_pad_numbers_are_jumpers no)
		(fp_line
			(start 0.508 -0.9398)
			(end -0.508 -0.9398)
			(stroke
				(width 0.1524)
				(type default)
			)
			(layer "F.SilkS")
		)
		(fp_line
			(start -0.508 -0.9398)
			(end -0.508 0.9398)
			(stroke
				(width 0.1524)
				(type default)
			)
			(layer "F.SilkS")
		)
		(fp_rect
			(start -0.508 0.9398)
			(end 0.508 -0.9398)
			(stroke
				(width 0)
				(type default)
			)
			(fill no)
			(layer "F.CrtYd")
		)
		(fp_rect
			(start -0.508 0.9398)
			(end 0.508 -0.9398)
			(stroke
				(width 0)
				(type default)
			)
			(fill no)
			(layer "F.Fab")
		)
		(pad "1" smd custom
			(at 0 -0.4445 180)
			(size 0.1397 0.1397)
			(layers "F.Cu" "F.Mask" "F.Paste")
			(net "TEMP_ALM#_JP_1")
			(options
				(clearance outline)
				(anchor circle)
			)
			(primitives
				(gr_poly
					(pts
						(arc
							(start -0.1778 -0.2794)
							(mid -0.249642 -0.249642)
							(end -0.2794 -0.1778)
						)
						(arc
							(start -0.2794 0.1778)
							(mid -0.249642 0.249642)
							(end -0.1778 0.2794)
						)
						(arc
							(start 0.1778 0.2794)
							(mid 0.249642 0.249642)
							(end 0.2794 0.1778)
						)
						(arc
							(start 0.2794 -0.1778)
							(mid 0.249642 -0.249642)
							(end 0.1778 -0.2794)
						)
					)
					(width 0)
					(fill yes)
				)
			)
		)
		(pad "2" smd custom
			(at 0 0.4445 180)
			(size 0.1397 0.1397)
			(layers "F.Cu" "F.Mask" "F.Paste")
			(net "TEMP_ALM#_REVERSE")
			(options
				(clearance outline)
				(anchor circle)
			)
			(primitives
				(gr_poly
					(pts
						(arc
							(start -0.1778 -0.2794)
							(mid -0.249642 -0.249642)
							(end -0.2794 -0.1778)
						)
						(arc
							(start -0.2794 0.1778)
							(mid -0.249642 0.249642)
							(end -0.1778 0.2794)
						)
						(arc
							(start 0.1778 0.2794)
							(mid 0.249642 0.249642)
							(end 0.2794 0.1778)
						)
						(arc
							(start 0.2794 -0.1778)
							(mid 0.249642 -0.249642)
							(end 0.1778 -0.2794)
						)
					)
					(width 0)
					(fill yes)
				)
			)
		)
	)
	(footprint ""
		(layer "F.Cu")
		(at 27.500072 -144.999964 90)
		(property "Reference" "Q1"
			(at 0 0 90)
			(layer "F.SilkS")
			(hide yes)
			(effects
				(font
					(size 1.27 1.27)
				)
			)
		)
		(property "Value" "PMBS3904-1-GP"
			(at 0 -9.0932 90)
			(unlocked yes)
			(layer "F.Fab")
			(hide yes)
			(effects
				(font
					(size 1.016 1.016)
					(thickness 0.1524)
				)
			)
		)
		(property "Device Type" "SOT-23-10H44"
			(at 0 -10.6172 90)
			(unlocked yes)
			(layer "F.Fab")
			(hide yes)
			(effects
				(font
					(size 1.016 1.016)
					(thickness 0.1524)
				)
			)
		)
		(duplicate_pad_numbers_are_jumpers no)
		(fp_line
			(start 1.651 -1.778)
			(end -1.651 -1.778)
			(stroke
				(width 0.1524)
				(type default)
			)
			(layer "F.SilkS")
		)
		(fp_line
			(start -1.651 -1.778)
			(end -1.651 1.778)
			(stroke
				(width 0.1524)
				(type default)
			)
			(layer "F.SilkS")
		)
		(fp_line
			(start 1.651 1.778)
			(end 1.651 -1.778)
			(stroke
				(width 0.1524)
				(type default)
			)
			(layer "F.SilkS")
		)
		(fp_line
			(start -1.651 1.778)
			(end 1.651 1.778)
			(stroke
				(width 0.1524)
				(type default)
			)
			(layer "F.SilkS")
		)
		(fp_line
			(start -0.9906 1.86309)
			(end -0.701294 2.15265)
			(stroke
				(width 0.0127)
				(type default)
			)
			(layer "F.SilkS")
		)
		(fp_line
			(start -0.994156 1.8669)
			(end -0.987044 1.8669)
			(stroke
				(width 0.0127)
				(type default)
			)
			(layer "F.SilkS")
		)
		(fp_line
			(start -1.003808 1.876552)
			(end -0.977646 1.876552)
			(stroke
				(width 0.0127)
				(type default)
			)
			(layer "F.SilkS")
		)
		(fp_line
			(start -0.635 1.8796)
			(end -1.7526 1.8796)
			(stroke
				(width 0.3302)
				(type default)
			)
			(layer "F.SilkS")
		)
		(fp_line
			(start -1.7526 1.8796)
			(end -1.7526 0.9906)
			(stroke
				(width 0.3302)
				(type default)
			)
			(layer "F.SilkS")
		)
		(fp_line
			(start -1.013206 1.88595)
			(end -0.967994 1.88595)
			(stroke
				(width 0.0127)
				(type default)
			)
			(layer "F.SilkS")
		)
		(fp_line
			(start -1.022858 1.895602)
			(end -0.958596 1.895602)
			(stroke
				(width 0.0127)
				(type default)
			)
			(layer "F.SilkS")
		)
		(fp_line
			(start -1.032256 1.905)
			(end -0.948944 1.905)
			(stroke
				(width 0.0127)
				(type default)
			)
			(layer "F.SilkS")
		)
		(fp_line
			(start -1.041908 1.914652)
			(end -0.939546 1.914652)
			(stroke
				(width 0.0127)
				(type default)
			)
			(layer "F.SilkS")
		)
		(fp_line
			(start -1.051306 1.92405)
			(end -0.929894 1.92405)
			(stroke
				(width 0.0127)
				(type default)
			)
			(layer "F.SilkS")
		)
		(fp_line
			(start -1.060958 1.933702)
			(end -0.920496 1.933702)
			(stroke
				(width 0.0127)
				(type default)
			)
			(layer "F.SilkS")
		)
		(fp_line
			(start -1.070356 1.9431)
			(end -0.910844 1.9431)
			(stroke
				(width 0.0127)
				(type default)
			)
			(layer "F.SilkS")
		)
		(fp_line
			(start -1.080008 1.952752)
			(end -0.901446 1.952752)
			(stroke
				(width 0.0127)
				(type default)
			)
			(layer "F.SilkS")
		)
		(fp_line
			(start -1.089406 1.96215)
			(end -0.891794 1.96215)
			(stroke
				(width 0.0127)
				(type default)
			)
			(layer "F.SilkS")
		)
		(fp_line
			(start -1.099058 1.971802)
			(end -0.882396 1.971802)
			(stroke
				(width 0.0127)
				(type default)
			)
			(layer "F.SilkS")
		)
		(fp_line
			(start -1.108456 1.9812)
			(end -0.872744 1.9812)
			(stroke
				(width 0.0127)
				(type default)
			)
			(layer "F.SilkS")
		)
		(fp_line
			(start -1.118108 1.990852)
			(end -0.863346 1.990852)
			(stroke
				(width 0.0127)
				(type default)
			)
			(layer "F.SilkS")
		)
		(fp_line
			(start -1.127506 2.00025)
			(end -0.853694 2.00025)
			(stroke
				(width 0.0127)
				(type default)
			)
			(layer "F.SilkS")
		)
		(fp_line
			(start -1.137158 2.009902)
			(end -0.844296 2.009902)
			(stroke
				(width 0.0127)
				(type default)
			)
			(layer "F.SilkS")
		)
		(fp_line
			(start -1.146556 2.0193)
			(end -0.834644 2.0193)
			(stroke
				(width 0.0127)
				(type default)
			)
			(layer "F.SilkS")
		)
		(fp_line
			(start -1.156208 2.028952)
			(end -0.825246 2.028952)
			(stroke
				(width 0.0127)
				(type default)
			)
			(layer "F.SilkS")
		)
		(fp_line
			(start -1.165606 2.03835)
			(end -0.815594 2.03835)
			(stroke
				(width 0.0127)
				(type default)
			)
			(layer "F.SilkS")
		)
		(fp_line
			(start -1.175258 2.048002)
			(end -0.806196 2.048002)
			(stroke
				(width 0.0127)
				(type default)
			)
			(layer "F.SilkS")
		)
		(fp_line
			(start -1.184656 2.0574)
			(end -0.796544 2.0574)
			(stroke
				(width 0.0127)
				(type default)
			)
			(layer "F.SilkS")
		)
		(fp_line
			(start -1.194308 2.067052)
			(end -0.787146 2.067052)
			(stroke
				(width 0.0127)
				(type default)
			)
			(layer "F.SilkS")
		)
		(fp_line
			(start -1.203706 2.07645)
			(end -0.777494 2.07645)
			(stroke
				(width 0.0127)
				(type default)
			)
			(layer "F.SilkS")
		)
		(fp_line
			(start -1.213358 2.086102)
			(end -0.768096 2.086102)
			(stroke
				(width 0.0127)
				(type default)
			)
			(layer "F.SilkS")
		)
		(fp_line
			(start -1.222756 2.0955)
			(end -0.758444 2.0955)
			(stroke
				(width 0.0127)
				(type default)
			)
			(layer "F.SilkS")
		)
		(fp_line
			(start -1.232408 2.105152)
			(end -0.749046 2.105152)
			(stroke
				(width 0.0127)
				(type default)
			)
			(layer "F.SilkS")
		)
		(fp_line
			(start -1.241806 2.11455)
			(end -0.739394 2.11455)
			(stroke
				(width 0.0127)
				(type default)
			)
			(layer "F.SilkS")
		)
		(fp_line
			(start -1.251458 2.124202)
			(end -0.729996 2.124202)
			(stroke
				(width 0.0127)
				(type default)
			)
			(layer "F.SilkS")
		)
		(fp_line
			(start -1.260856 2.1336)
			(end -0.720344 2.1336)
			(stroke
				(width 0.0127)
				(type default)
			)
			(layer "F.SilkS")
		)
		(fp_line
			(start -0.719074 2.145538)
			(end -1.265936 2.14122)
			(stroke
				(width 0.0127)
				(type default)
			)
			(layer "F.SilkS")
		)
		(fp_line
			(start -1.279398 2.152142)
			(end -0.9906 1.86309)
			(stroke
				(width 0.0127)
				(type default)
			)
			(layer "F.SilkS")
		)
		(fp_line
			(start -0.71628 2.15265)
			(end -1.26492 2.15265)
			(stroke
				(width 0.0127)
				(type default)
			)
			(layer "F.SilkS")
		)
		(fp_line
			(start -1.279144 2.15265)
			(end -0.701294 2.15265)
			(stroke
				(width 0.0127)
				(type default)
			)
			(layer "F.SilkS")
		)
		(fp_poly
			(pts
				(xy -1.285748 2.159) (xy -1.285748 1.8796) (xy -1.778 1.8796) (xy -1.778 -1.8796) (xy 1.778 -1.8796)
				(xy 1.778 1.8796) (xy -0.694944 1.8796) (xy -0.694944 2.159)
			)
			(stroke
				(width 0)
				(type default)
			)
			(fill no)
			(layer "F.CrtYd")
		)
		(fp_poly
			(pts
				(xy -1.285748 2.159) (xy -1.285748 1.8796) (xy -1.778 1.8796) (xy -1.778 -1.8796) (xy 1.778 -1.8796)
				(xy 1.778 1.8796) (xy -0.694944 1.8796) (xy -0.694944 2.159)
			)
			(stroke
				(width 0)
				(type default)
			)
			(fill no)
			(layer "F.Fab")
		)
		(pad "1" smd rect
			(at -0.98425 0.9525 90)
			(size 0.762 1.143)
			(layers "F.Cu" "F.Mask" "F.Paste")
			(net "NCT7904_D1+")
		)
		(pad "2" smd rect
			(at 0.98425 0.9525 90)
			(size 0.762 1.143)
			(layers "F.Cu" "F.Mask" "F.Paste")
			(net "NCT7904_D1-")
		)
		(pad "3" smd rect
			(at 0 -0.9525 90)
			(size 0.762 1.143)
			(layers "F.Cu" "F.Mask" "F.Paste")
			(net "NCT7904_D1+")
		)
	)
	(footprint ""
		(layer "F.Cu")
		(at 39.8018 -159.2072 90)
		(property "Reference" "TP12"
			(at 0 0 90)
			(layer "F.SilkS")
			(hide yes)
			(effects
				(font
					(size 1.27 1.27)
				)
			)
		)
		(property "Value" "TPAD32-GP"
			(at 0 -3.166364 90)
			(unlocked yes)
			(layer "F.Fab")
			(hide yes)
			(effects
				(font
					(size 1.016 1.016)
					(thickness 0.1524)
				)
			)
		)
		(property "Device Type" "TPAD32"
			(at 0 -4.690618 90)
			(unlocked yes)
			(layer "F.Fab")
			(hide yes)
			(effects
				(font
					(size 1.016 1.016)
					(thickness 0.1524)
				)
			)
		)
		(duplicate_pad_numbers_are_jumpers no)
		(fp_poly
			(pts
				(arc
					(start 0 0.7112)
					(mid 0 -0.7112)
					(end 0 0.7112)
				)
			)
			(stroke
				(width 0)
				(type default)
			)
			(fill no)
			(layer "F.CrtYd")
		)
		(fp_poly
			(pts
				(arc
					(start 0 0.7112)
					(mid 0 -0.7112)
					(end 0 0.7112)
				)
			)
			(stroke
				(width 0)
				(type default)
			)
			(fill no)
			(layer "F.Fab")
		)
		(pad "1" smd circle
			(at 0 0 90)
			(size 0.8128 0.8128)
			(layers "F.Cu" "F.Mask" "F.Paste")
			(net "NCT7904_PECI")
		)
	)
)
